(kicad_pcb
	(version 20241229)
	(generator "pcbnew")
	(generator_version "9.0")
	(general
		(thickness 1.6)
		(legacy_teardrops no)
	)
	(paper "A4")
	(title_block
		(title "OCuLink to PCIe adapter")
		(date "2025-06-18")
		(rev "1.0.0")
		(company "Antmicro Ltd")
		(comment 1 "www.antmicro.com")
		(comment 9 "footprints 157-159 of 159")
	)
	(layers
		(0 "F.Cu" signal)
		(4 "In1.Cu" signal)
		(6 "In2.Cu" signal)
		(2 "B.Cu" signal)
		(9 "F.Adhes" user "F.Adhesive")
		(11 "B.Adhes" user "B.Adhesive")
		(13 "F.Paste" user)
		(15 "B.Paste" user)
		(5 "F.SilkS" user "F.Silkscreen")
		(7 "B.SilkS" user "B.Silkscreen")
		(1 "F.Mask" user)
		(3 "B.Mask" user)
		(17 "Dwgs.User" user "User.Drawings")
		(19 "Cmts.User" user "User.Comments")
		(21 "Eco1.User" user "User.Eco1")
		(23 "Eco2.User" user "User.Eco2")
		(25 "Edge.Cuts" user)
		(27 "Margin" user)
		(31 "F.CrtYd" user "F.Courtyard")
		(29 "B.CrtYd" user "B.Courtyard")
		(35 "F.Fab" user)
		(33 "B.Fab" user)
	)
	(footprint "antmicro-footprints:R_0402_1005Metric"
		(layer "F.Cu")
		(at 136.75 68.05 90)
		(descr "Resistor SMD 0402")
		(tags "resistor SMD 0402")
		(property "Reference" "R48"
			(at 1.299999 -5.499499 90)
			(layer "F.SilkS")
			(effects
				(font
					(size 0.7 0.7)
					(thickness 0.15)
				)
				(justify right top)
			)
		)
		(property "Value" "R_1k_0402"
			(at -1.011843 1.772046 90)
			(layer "F.Fab")
			(effects
				(font
					(size 0.7 0.7)
					(thickness 0.15)
				)
				(justify left bottom)
			)
		)
		(property "Datasheet" "https://www.bourns.com/docs/product-datasheets/cr.pdf"
			(at 0 0 90)
			(layer "F.Fab")
			(hide yes)
			(effects
				(font
					(size 1.27 1.27)
					(thickness 0.15)
				)
			)
		)
		(property "Description" "SMD Chip Resistor, 1 kohm, ± 1%, 63 mW, 0402 [1005 Metric], Thick Film, General Purpose"
			(at 0 0 90)
			(layer "F.Fab")
			(hide yes)
			(effects
				(font
					(size 1.27 1.27)
					(thickness 0.15)
				)
			)
		)
		(property "MPN" "CR0402-FX-1001GLF"
			(at 0 0 90)
			(unlocked yes)
			(layer "F.Fab")
			(hide yes)
			(effects
				(font
					(size 1 1)
					(thickness 0.15)
				)
			)
		)
		(property "Manufacturer" "Bourns"
			(at 0 0 90)
			(unlocked yes)
			(layer "F.Fab")
			(hide yes)
			(effects
				(font
					(size 1 1)
					(thickness 0.15)
				)
			)
		)
		(property "License" "Apache-2.0"
			(at 0 0 90)
			(unlocked yes)
			(layer "F.Fab")
			(hide yes)
			(effects
				(font
					(size 1 1)
					(thickness 0.15)
				)
			)
		)
		(property "Author" "Antmicro"
			(at 0 0 90)
			(unlocked yes)
			(layer "F.Fab")
			(hide yes)
			(effects
				(font
					(size 1 1)
					(thickness 0.15)
				)
			)
		)
		(property "Val" "1k"
			(at 0 0 90)
			(unlocked yes)
			(layer "F.Fab")
			(hide yes)
			(effects
				(font
					(size 1 1)
					(thickness 0.15)
				)
			)
		)
		(property "Tolerance" "1%"
			(at 0 0 90)
			(unlocked yes)
			(layer "F.Fab")
			(hide yes)
			(effects
				(font
					(size 1 1)
					(thickness 0.15)
				)
			)
		)
		(sheetname "/USB-PD/")
		(sheetfile "usb-pd.kicad_sch")
		(attr smd)
		(fp_rect
			(start -0.925 -0.47)
			(end 0.925 0.47)
			(stroke
				(width 0.05)
				(type default)
			)
			(fill no)
			(layer "F.CrtYd")
		)
		(fp_rect
			(start -0.5 -0.25)
			(end 0.5 0.25)
			(stroke
				(width 0.15)
				(type solid)
			)
			(fill no)
			(layer "F.Fab")
		)
		(fp_text user "Author: Antmicro"
			(at -0.95 4.169 90)
			(layer "F.Fab")
			(effects
				(font
					(size 0.7 0.7)
					(thickness 0.15)
				)
				(justify left bottom)
			)
		)
		(fp_text user "${REFERENCE}"
			(at 0 0 270)
			(layer "F.Fab")
			(effects
				(font
					(size 0.7 0.7)
					(thickness 0.15)
				)
				(justify right top)
			)
		)
		(fp_text user "License: Apache-2.0"
			(at -0.949999 5.169 90)
			(layer "F.Fab")
			(effects
				(font
					(size 0.7 0.7)
					(thickness 0.15)
				)
				(justify left bottom)
			)
		)
		(pad "1" smd roundrect
			(at -0.48 0 90)
			(size 0.59 0.64)
			(layers "F.Cu" "F.Mask" "F.Paste")
			(roundrect_rratio 0.25)
			(net 173 "/USB-PD/~{FAULT}")
			(pintype "passive")
		)
		(pad "2" smd roundrect
			(at 0.48 0 90)
			(size 0.59 0.64)
			(layers "F.Cu" "F.Mask" "F.Paste")
			(roundrect_rratio 0.25)
			(net 117 "/USB-PD/VDDD_3V3")
			(pintype "passive")
		)
	)
	(footprint "antmicro-footprints:R_0402_1005Metric"
		(layer "F.Cu")
		(at 140.6 50.8 -90)
		(descr "Resistor SMD 0402")
		(tags "resistor SMD 0402")
		(property "Reference" "R1"
			(at 0.95 0.4 270)
			(layer "F.SilkS")
			(effects
				(font
					(size 0.7 0.7)
					(thickness 0.15)
				)
				(justify right top)
			)
		)
		(property "Value" "R_0R_0402"
			(at -1.011843 1.772046 90)
			(layer "F.Fab")
			(effects
				(font
					(size 0.7 0.7)
					(thickness 0.15)
				)
				(justify right top)
			)
		)
		(property "Datasheet" "https://industrial.panasonic.com/cdbs/www-data/pdf/RDA0000/AOA0000C301.pdf"
			(at 0 0 90)
			(layer "F.Fab")
			(hide yes)
			(effects
				(font
					(size 1.27 1.27)
					(thickness 0.15)
				)
			)
		)
		(property "Description" "SMD Chip Resistor, Jumper, 0 ohm, 100 mW, 0402 [1005 Metric], Thick Film, General Purpose"
			(at 0 0 90)
			(layer "F.Fab")
			(hide yes)
			(effects
				(font
					(size 1.27 1.27)
					(thickness 0.15)
				)
			)
		)
		(property "MPN" "ERJ2GE0R00X"
			(at 0 0 270)
			(unlocked yes)
			(layer "F.Fab")
			(hide yes)
			(effects
				(font
					(size 1 1)
					(thickness 0.15)
				)
			)
		)
		(property "Manufacturer" "Panasonic"
			(at 0 0 270)
			(unlocked yes)
			(layer "F.Fab")
			(hide yes)
			(effects
				(font
					(size 1 1)
					(thickness 0.15)
				)
			)
		)
		(property "License" "Apache-2.0"
			(at 0 0 270)
			(unlocked yes)
			(layer "F.Fab")
			(hide yes)
			(effects
				(font
					(size 1 1)
					(thickness 0.15)
				)
			)
		)
		(property "Author" "Antmicro"
			(at 0 0 270)
			(unlocked yes)
			(layer "F.Fab")
			(hide yes)
			(effects
				(font
					(size 1 1)
					(thickness 0.15)
				)
			)
		)
		(property "Val" "0R"
			(at 0 0 270)
			(unlocked yes)
			(layer "F.Fab")
			(hide yes)
			(effects
				(font
					(size 1 1)
					(thickness 0.15)
				)
			)
		)
		(property "Tolerance" ""
			(at 0 0 270)
			(unlocked yes)
			(layer "F.Fab")
			(hide yes)
			(effects
				(font
					(size 1 1)
					(thickness 0.15)
				)
			)
		)
		(property "Current" "1A"
			(at 0 0 270)
			(unlocked yes)
			(layer "F.Fab")
			(hide yes)
			(effects
				(font
					(size 1 1)
					(thickness 0.15)
				)
			)
		)
		(sheetname "/OCuLink/")
		(sheetfile "oculink.kicad_sch")
		(attr smd dnp)
		(fp_rect
			(start -0.925 -0.47)
			(end 0.925 0.47)
			(stroke
				(width 0.05)
				(type default)
			)
			(fill no)
			(layer "F.CrtYd")
		)
		(fp_rect
			(start -0.5 -0.25)
			(end 0.5 0.25)
			(stroke
				(width 0.15)
				(type solid)
			)
			(fill no)
			(layer "F.Fab")
		)
		(fp_text user "${REFERENCE}"
			(at 0 0 90)
			(layer "F.Fab")
			(effects
				(font
					(size 0.7 0.7)
					(thickness 0.15)
				)
				(justify right top)
			)
		)
		(fp_text user "License: Apache-2.0"
			(at -0.949999 5.169 90)
			(layer "F.Fab")
			(effects
				(font
					(size 0.7 0.7)
					(thickness 0.15)
				)
				(justify right top)
			)
		)
		(fp_text user "Author: Antmicro"
			(at -0.95 4.169 90)
			(layer "F.Fab")
			(effects
				(font
					(size 0.7 0.7)
					(thickness 0.15)
				)
				(justify right top)
			)
		)
		(pad "1" smd roundrect
			(at -0.48 0 270)
			(size 0.59 0.64)
			(layers "F.Cu" "F.Mask" "F.Paste")
			(roundrect_rratio 0.25)
			(net 101 "/OCuLink/I2C0C_SCL")
			(pintype "passive")
		)
		(pad "2" smd roundrect
			(at 0.48 0 270)
			(size 0.59 0.64)
			(layers "F.Cu" "F.Mask" "F.Paste")
			(roundrect_rratio 0.25)
			(net 102 "/OCuLink/I2C0.SCL")
			(pintype "passive")
		)
	)
	(footprint "antmicro-footprints:R_0402_1005Metric"
		(layer "F.Cu")
		(at 148.151999 93.000001 180)
		(descr "Resistor SMD 0402")
		(tags "resistor SMD 0402")
		(property "Reference" "R33"
			(at -3.448001 0.400001 180)
			(layer "F.SilkS")
			(effects
				(font
					(size 0.7 0.7)
					(thickness 0.15)
				)
				(justify right top)
			)
		)
		(property "Value" "R_158k_0402"
			(at -1.011843 1.772046 0)
			(layer "F.Fab")
			(effects
				(font
					(size 0.7 0.7)
					(thickness 0.15)
				)
				(justify right top)
			)
		)
		(property "Datasheet" "https://www.bourns.com/docs/product-datasheets/cr.pdf"
			(at 0 0 0)
			(layer "F.Fab")
			(hide yes)
			(effects
				(font
					(size 1.27 1.27)
					(thickness 0.15)
				)
			)
		)
		(property "Description" "SMD Chip Resistor, 158 kohm, ± 1%, 100 mW, 0402 [1005 Metric], Thick Film, Precision"
			(at 0 0 0)
			(layer "F.Fab")
			(hide yes)
			(effects
				(font
					(size 1.27 1.27)
					(thickness 0.15)
				)
			)
		)
		(property "MPN" "CR0402-FX-1583GLF"
			(at 0 0 180)
			(unlocked yes)
			(layer "F.Fab")
			(hide yes)
			(effects
				(font
					(size 1 1)
					(thickness 0.15)
				)
			)
		)
		(property "Manufacturer" "Bourns"
			(at 0 0 180)
			(unlocked yes)
			(layer "F.Fab")
			(hide yes)
			(effects
				(font
					(size 1 1)
					(thickness 0.15)
				)
			)
		)
		(property "License" "Apache-2.0"
			(at 0 0 180)
			(unlocked yes)
			(layer "F.Fab")
			(hide yes)
			(effects
				(font
					(size 1 1)
					(thickness 0.15)
				)
			)
		)
		(property "Author" "Antmicro"
			(at 0 0 180)
			(unlocked yes)
			(layer "F.Fab")
			(hide yes)
			(effects
				(font
					(size 1 1)
					(thickness 0.15)
				)
			)
		)
		(property "Val" "158k"
			(at 0 0 180)
			(unlocked yes)
			(layer "F.Fab")
			(hide yes)
			(effects
				(font
					(size 1 1)
					(thickness 0.15)
				)
			)
		)
		(property "Tolerance" "1%"
			(at 0 0 180)
			(unlocked yes)
			(layer "F.Fab")
			(hide yes)
			(effects
				(font
					(size 1 1)
					(thickness 0.15)
				)
			)
		)
		(sheetname "/USB-PD/")
		(sheetfile "usb-pd.kicad_sch")
		(attr smd)
		(fp_rect
			(start -0.925 -0.47)
			(end 0.925 0.47)
			(stroke
				(width 0.05)
				(type default)
			)
			(fill no)
			(layer "F.CrtYd")
		)
		(fp_rect
			(start -0.5 -0.25)
			(end 0.5 0.25)
			(stroke
				(width 0.15)
				(type solid)
			)
			(fill no)
			(layer "F.Fab")
		)
		(fp_text user "${REFERENCE}"
			(at 0 0 0)
			(layer "F.Fab")
			(effects
				(font
					(size 0.7 0.7)
					(thickness 0.15)
				)
				(justify right top)
			)
		)
		(fp_text user "Author: Antmicro"
			(at -0.95 4.169 0)
			(layer "F.Fab")
			(effects
				(font
					(size 0.7 0.7)
					(thickness 0.15)
				)
				(justify right top)
			)
		)
		(fp_text user "License: Apache-2.0"
			(at -0.949999 5.169 0)
			(layer "F.Fab")
			(effects
				(font
					(size 0.7 0.7)
					(thickness 0.15)
				)
				(justify right top)
			)
		)
		(pad "1" smd roundrect
			(at -0.48 0 180)
			(size 0.59 0.64)
			(layers "F.Cu" "F.Mask" "F.Paste")
			(roundrect_rratio 0.25)
			(net 66 "GND")
			(pintype "passive")
		)
		(pad "2" smd roundrect
			(at 0.48 0 180)
			(size 0.59 0.64)
			(layers "F.Cu" "F.Mask" "F.Paste")
			(roundrect_rratio 0.25)
			(net 157 "/USB-PD/12V_FSW")
			(pintype "passive")
		)
	)
)
